# S9S_MB_2U (Grand Teton) — schematic netlist excerpt (pin names and nets, part order shuffled) for the footprints in the layout excerpt that follows; sources: Cadence DE-HDL packaged netlist, KiCad conversion of 03242023_DA0F0TMBIJ0_F0T_Motherboard_J_brd_V01_OCP.brd

PR3947  Q_RES  2.8K 1% EMPTY  pkg 0402LF  page 193 : A = GND ; B = P3V3_E1S_ILIMIT_0
R1921  Q_RES  33.2 1% CHIP  pkg 0402LF  page 158 : A = FM_SMB_CPU0_ALERT ; B = FM_SMB_PEHPCPU0_PCIE_ALERT_N

(kicad_pcb
	(version 20260206)
	(generator "pcbnew")
	(generator_version "10.0")
	(general
		(thickness 1.6)
		(legacy_teardrops no)
	)
	(paper "A4")
	(title_block
		(title "03242023_DA0F0TMBIJ0_F0T_Motherboard_J_brd_V01_OCP.brd")
		(comment 1 "Grand Teton / footprints 3159-3160 of 6105")
	)
	(layers
		(0 "F.Cu" signal "TOP")
		(4 "In1.Cu" signal "GND")
		(6 "In2.Cu" signal "IN1")
		(8 "In3.Cu" signal "GND1")
		(10 "In4.Cu" signal "IN2")
		(12 "In5.Cu" signal "GND2")
		(14 "In6.Cu" signal "IN3")
		(16 "In7.Cu" signal "GND3")
		(18 "In8.Cu" signal "VCC")
		(20 "In9.Cu" signal "VCC1")
		(22 "In10.Cu" signal "GND4")
		(24 "In11.Cu" signal "IN4")
		(26 "In12.Cu" signal "GND5")
		(28 "In13.Cu" signal "IN5")
		(30 "In14.Cu" signal "GND6")
		(32 "In15.Cu" signal "IN6")
		(34 "In16.Cu" signal "GND7")
		(2 "B.Cu" signal "BOTTOM")
		(9 "F.Adhes" user "F.Adhesive")
		(11 "B.Adhes" user "B.Adhesive")
		(13 "F.Paste" user "Package Geometry/Pastemask Top")
		(15 "B.Paste" user "Package Geometry/Pastemask Bottom")
		(5 "F.SilkS" user "Ref Des/Silkscreen Top")
		(7 "B.SilkS" user "Ref Des/Silkscreen Bottom")
		(1 "F.Mask" user "Board Geometry/Soldermask Top")
		(3 "B.Mask" user "Board Geometry/Soldermask Bottom")
		(17 "Dwgs.User" user "User.Drawings")
		(19 "Cmts.User" user "User.Comments")
		(21 "Eco1.User" user "User.Eco1")
		(23 "Eco2.User" user "User.Eco2")
		(25 "Edge.Cuts" user "Board Geometry/Outline")
		(27 "Margin" user)
		(31 "F.CrtYd" user "Package Geometry/Place Bound Top")
		(29 "B.CrtYd" user "Package Geometry/Place Bound Bottom")
		(35 "F.Fab" user "Ref Des/Assembly Top")
		(33 "B.Fab" user "Ref Des/Assembly Bottom")
	)
	(footprint ""
		(layer "F.Cu")
		(at 449.973954 -119.429022 180)
		(property "Reference" "R1921"
			(at 0 0 180)
			(layer "F.SilkS")
			(hide yes)
			(effects
				(font
					(size 1.27 1.27)
				)
			)
		)
		(property "Value" ""
			(at 0 0 180)
			(layer "F.Fab")
			(effects
				(font
					(size 1.27 1.27)
				)
			)
		)
		(duplicate_pad_numbers_are_jumpers no)
		(fp_line
			(start 0.7874 0.4064)
			(end -0.7874 0.4064)
			(stroke
				(width 0.1524)
				(type default)
			)
			(layer "F.SilkS")
		)
		(fp_line
			(start 0.7874 -0.4064)
			(end 0.7874 0.4064)
			(stroke
				(width 0.1524)
				(type default)
			)
			(layer "F.SilkS")
		)
		(fp_line
			(start -0.7874 0.4064)
			(end -0.7874 -0.4064)
			(stroke
				(width 0.1524)
				(type default)
			)
			(layer "F.SilkS")
		)
		(fp_line
			(start -0.7874 -0.4064)
			(end 0.7874 -0.4064)
			(stroke
				(width 0.1524)
				(type default)
			)
			(layer "F.SilkS")
		)
		(fp_line
			(start 0.67945 0.3048)
			(end 0.120396 0.3048)
			(stroke
				(width 0.1)
				(type default)
			)
			(layer "F.Fab")
		)
		(fp_line
			(start 0.67945 -0.3048)
			(end 0.67945 0.3048)
			(stroke
				(width 0.1)
				(type default)
			)
			(layer "F.Fab")
		)
		(fp_line
			(start 0.12065 -0.2794)
			(end 0.12065 -0.3048)
			(stroke
				(width 0.1)
				(type default)
			)
			(layer "F.Fab")
		)
		(fp_line
			(start 0.12065 -0.3048)
			(end 0.67945 -0.3048)
			(stroke
				(width 0.1)
				(type default)
			)
			(layer "F.Fab")
		)
		(fp_line
			(start 0.120396 0.3048)
			(end 0.120396 0.2794)
			(stroke
				(width 0.1)
				(type default)
			)
			(layer "F.Fab")
		)
		(fp_line
			(start 0.120396 0.2794)
			(end -0.12065 0.2794)
			(stroke
				(width 0.1)
				(type default)
			)
			(layer "F.Fab")
		)
		(fp_line
			(start -0.12065 0.3048)
			(end -0.67945 0.3048)
			(stroke
				(width 0.1)
				(type default)
			)
			(layer "F.Fab")
		)
		(fp_line
			(start -0.12065 0.2794)
			(end -0.12065 0.3048)
			(stroke
				(width 0.1)
				(type default)
			)
			(layer "F.Fab")
		)
		(fp_line
			(start -0.12065 -0.2794)
			(end 0.12065 -0.2794)
			(stroke
				(width 0.1)
				(type default)
			)
			(layer "F.Fab")
		)
		(fp_line
			(start -0.12065 -0.305054)
			(end -0.12065 -0.2794)
			(stroke
				(width 0.1)
				(type default)
			)
			(layer "F.Fab")
		)
		(fp_line
			(start -0.67945 0.3048)
			(end -0.67945 -0.305054)
			(stroke
				(width 0.1)
				(type default)
			)
			(layer "F.Fab")
		)
		(fp_line
			(start -0.67945 -0.305054)
			(end -0.12065 -0.305054)
			(stroke
				(width 0.1)
				(type default)
			)
			(layer "F.Fab")
		)
		(pad "1" smd circle
			(at -0.40005 0 180)
			(size 0 0)
			(layers "F.Cu" "F.Mask" "F.Paste")
			(net "FM_SMB_CPU0_ALERT")
		)
		(pad "2" smd circle
			(at 0.40005 0 180)
			(size 0 0)
			(layers "F.Cu" "F.Mask" "F.Paste")
			(net "FM_SMB_PEHPCPU0_PCIE_ALERT_N")
		)
	)
	(footprint ""
		(layer "F.Cu")
		(at 190.41364 -70.185788)
		(property "Reference" "PR3947"
			(at 0 0 0)
			(layer "F.SilkS")
			(hide yes)
			(effects
				(font
					(size 1.27 1.27)
				)
			)
		)
		(property "Value" ""
			(at 0 0 0)
			(layer "F.Fab")
			(effects
				(font
					(size 1.27 1.27)
				)
			)
		)
		(duplicate_pad_numbers_are_jumpers no)
		(fp_line
			(start -0.7874 -0.4064)
			(end 0.7874 -0.4064)
			(stroke
				(width 0.1524)
				(type default)
			)
			(layer "F.SilkS")
		)
		(fp_line
			(start -0.7874 0.4064)
			(end -0.7874 -0.4064)
			(stroke
				(width 0.1524)
				(type default)
			)
			(layer "F.SilkS")
		)
		(fp_line
			(start 0.7874 -0.4064)
			(end 0.7874 0.4064)
			(stroke
				(width 0.1524)
				(type default)
			)
			(layer "F.SilkS")
		)
		(fp_line
			(start 0.7874 0.4064)
			(end -0.7874 0.4064)
			(stroke
				(width 0.1524)
				(type default)
			)
			(layer "F.SilkS")
		)
		(fp_line
			(start -0.67945 -0.305054)
			(end -0.12065 -0.305054)
			(stroke
				(width 0.1)
				(type default)
			)
			(layer "F.Fab")
		)
		(fp_line
			(start -0.67945 0.3048)
			(end -0.67945 -0.305054)
			(stroke
				(width 0.1)
				(type default)
			)
			(layer "F.Fab")
		)
		(fp_line
			(start -0.12065 -0.305054)
			(end -0.12065 -0.2794)
			(stroke
				(width 0.1)
				(type default)
			)
			(layer "F.Fab")
		)
		(fp_line
			(start -0.12065 -0.2794)
			(end 0.12065 -0.2794)
			(stroke
				(width 0.1)
				(type default)
			)
			(layer "F.Fab")
		)
		(fp_line
			(start -0.12065 0.2794)
			(end -0.12065 0.3048)
			(stroke
				(width 0.1)
				(type default)
			)
			(layer "F.Fab")
		)
		(fp_line
			(start -0.12065 0.3048)
			(end -0.67945 0.3048)
			(stroke
				(width 0.1)
				(type default)
			)
			(layer "F.Fab")
		)
		(fp_line
			(start 0.120396 0.2794)
			(end -0.12065 0.2794)
			(stroke
				(width 0.1)
				(type default)
			)
			(layer "F.Fab")
		)
		(fp_line
			(start 0.120396 0.3048)
			(end 0.120396 0.2794)
			(stroke
				(width 0.1)
				(type default)
			)
			(layer "F.Fab")
		)
		(fp_line
			(start 0.12065 -0.3048)
			(end 0.67945 -0.3048)
			(stroke
				(width 0.1)
				(type default)
			)
			(layer "F.Fab")
		)
		(fp_line
			(start 0.12065 -0.2794)
			(end 0.12065 -0.3048)
			(stroke
				(width 0.1)
				(type default)
			)
			(layer "F.Fab")
		)
		(fp_line
			(start 0.67945 -0.3048)
			(end 0.67945 0.3048)
			(stroke
				(width 0.1)
				(type default)
			)
			(layer "F.Fab")
		)
		(fp_line
			(start 0.67945 0.3048)
			(end 0.120396 0.3048)
			(stroke
				(width 0.1)
				(type default)
			)
			(layer "F.Fab")
		)
		(pad "1" smd circle
			(at -0.40005 0)
			(size 0 0)
			(layers "F.Cu" "F.Mask" "F.Paste")
			(net "GND")
		)
		(pad "2" smd circle
			(at 0.40005 0)
			(size 0 0)
			(layers "F.Cu" "F.Mask" "F.Paste")
			(net "P3V3_E1S_ILIMIT_0")
		)
	)
)
